(kicad_pcb
	(version 20260206)
	(generator "pcbnew")
	(generator_version "10.0")
	(general
		(thickness 1.6)
		(legacy_teardrops no)
	)
	(paper "A4")
	(title_block
		(title "03242023_DA0F0TMBIJ0_F0T_Motherboard_J_brd_V01_OCP.brd")
		(comment 1 "Grand Teton / footprints 3084-3089 of 6105")
	)
	(layers
		(0 "F.Cu" signal "TOP")
		(4 "In1.Cu" signal "GND")
		(6 "In2.Cu" signal "IN1")
		(8 "In3.Cu" signal "GND1")
		(10 "In4.Cu" signal "IN2")
		(12 "In5.Cu" signal "GND2")
		(14 "In6.Cu" signal "IN3")
		(16 "In7.Cu" signal "GND3")
		(18 "In8.Cu" signal "VCC")
		(20 "In9.Cu" signal "VCC1")
		(22 "In10.Cu" signal "GND4")
		(24 "In11.Cu" signal "IN4")
		(26 "In12.Cu" signal "GND5")
		(28 "In13.Cu" signal "IN5")
		(30 "In14.Cu" signal "GND6")
		(32 "In15.Cu" signal "IN6")
		(34 "In16.Cu" signal "GND7")
		(2 "B.Cu" signal "BOTTOM")
		(9 "F.Adhes" user "F.Adhesive")
		(11 "B.Adhes" user "B.Adhesive")
		(13 "F.Paste" user "Package Geometry/Pastemask Top")
		(15 "B.Paste" user "Package Geometry/Pastemask Bottom")
		(5 "F.SilkS" user "Ref Des/Silkscreen Top")
		(7 "B.SilkS" user "Ref Des/Silkscreen Bottom")
		(1 "F.Mask" user "Board Geometry/Soldermask Top")
		(3 "B.Mask" user "Board Geometry/Soldermask Bottom")
		(17 "Dwgs.User" user "User.Drawings")
		(19 "Cmts.User" user "User.Comments")
		(21 "Eco1.User" user "User.Eco1")
		(23 "Eco2.User" user "User.Eco2")
		(25 "Edge.Cuts" user "Board Geometry/Outline")
		(27 "Margin" user)
		(31 "F.CrtYd" user "Package Geometry/Place Bound Top")
		(29 "B.CrtYd" user "Package Geometry/Place Bound Bottom")
		(35 "F.Fab" user "Ref Des/Assembly Top")
		(33 "B.Fab" user "Ref Des/Assembly Bottom")
	)
	(footprint ""
		(layer "F.Cu")
		(at 365.46663 -244.03177 90)
		(property "Reference" "C1013"
			(at 0 0 90)
			(layer "F.SilkS")
			(hide yes)
			(effects
				(font
					(size 1.27 1.27)
				)
			)
		)
		(property "Value" ""
			(at 0 0 90)
			(layer "F.Fab")
			(effects
				(font
					(size 1.27 1.27)
				)
			)
		)
		(duplicate_pad_numbers_are_jumpers no)
		(fp_line
			(start 0.7874 -0.4064)
			(end 0.7874 0.4064)
			(stroke
				(width 0.1524)
				(type default)
			)
			(layer "F.SilkS")
		)
		(fp_line
			(start -0.7874 -0.4064)
			(end 0.7874 -0.4064)
			(stroke
				(width 0.1524)
				(type default)
			)
			(layer "F.SilkS")
		)
		(fp_line
			(start 0.7874 0.4064)
			(end -0.7874 0.4064)
			(stroke
				(width 0.1524)
				(type default)
			)
			(layer "F.SilkS")
		)
		(fp_line
			(start -0.7874 0.4064)
			(end -0.7874 -0.4064)
			(stroke
				(width 0.1524)
				(type default)
			)
			(layer "F.SilkS")
		)
		(fp_line
			(start -0.12065 -0.305054)
			(end -0.12065 -0.2794)
			(stroke
				(width 0.1)
				(type default)
			)
			(layer "F.Fab")
		)
		(fp_line
			(start -0.67945 -0.305054)
			(end -0.12065 -0.305054)
			(stroke
				(width 0.1)
				(type default)
			)
			(layer "F.Fab")
		)
		(fp_line
			(start 0.67945 -0.3048)
			(end 0.67945 0.3048)
			(stroke
				(width 0.1)
				(type default)
			)
			(layer "F.Fab")
		)
		(fp_line
			(start 0.12065 -0.3048)
			(end 0.67945 -0.3048)
			(stroke
				(width 0.1)
				(type default)
			)
			(layer "F.Fab")
		)
		(fp_line
			(start 0.12065 -0.2794)
			(end 0.12065 -0.3048)
			(stroke
				(width 0.1)
				(type default)
			)
			(layer "F.Fab")
		)
		(fp_line
			(start -0.12065 -0.2794)
			(end 0.12065 -0.2794)
			(stroke
				(width 0.1)
				(type default)
			)
			(layer "F.Fab")
		)
		(fp_line
			(start 0.120396 0.2794)
			(end -0.12065 0.2794)
			(stroke
				(width 0.1)
				(type default)
			)
			(layer "F.Fab")
		)
		(fp_line
			(start -0.12065 0.2794)
			(end -0.12065 0.3048)
			(stroke
				(width 0.1)
				(type default)
			)
			(layer "F.Fab")
		)
		(fp_line
			(start 0.67945 0.3048)
			(end 0.120396 0.3048)
			(stroke
				(width 0.1)
				(type default)
			)
			(layer "F.Fab")
		)
		(fp_line
			(start 0.120396 0.3048)
			(end 0.120396 0.2794)
			(stroke
				(width 0.1)
				(type default)
			)
			(layer "F.Fab")
		)
		(fp_line
			(start -0.12065 0.3048)
			(end -0.67945 0.3048)
			(stroke
				(width 0.1)
				(type default)
			)
			(layer "F.Fab")
		)
		(fp_line
			(start -0.67945 0.3048)
			(end -0.67945 -0.305054)
			(stroke
				(width 0.1)
				(type default)
			)
			(layer "F.Fab")
		)
		(pad "1" smd circle
			(at -0.40005 0 90)
			(size 0 0)
			(layers "F.Cu" "F.Mask" "F.Paste")
			(net "PVCCIN_CPU0")
		)
		(pad "2" smd circle
			(at 0.40005 0 90)
			(size 0 0)
			(layers "F.Cu" "F.Mask" "F.Paste")
			(net "GND")
		)
	)
	(footprint ""
		(layer "F.Cu")
		(at 167.395906 -131.976114 90)
		(property "Reference" "R1641"
			(at 0 0 90)
			(layer "F.SilkS")
			(hide yes)
			(effects
				(font
					(size 1.27 1.27)
				)
			)
		)
		(property "Value" ""
			(at 0 0 90)
			(layer "F.Fab")
			(effects
				(font
					(size 1.27 1.27)
				)
			)
		)
		(duplicate_pad_numbers_are_jumpers no)
		(fp_line
			(start 0.7874 -0.4064)
			(end 0.7874 0.4064)
			(stroke
				(width 0.1524)
				(type default)
			)
			(layer "F.SilkS")
		)
		(fp_line
			(start -0.7874 -0.4064)
			(end 0.7874 -0.4064)
			(stroke
				(width 0.1524)
				(type default)
			)
			(layer "F.SilkS")
		)
		(fp_line
			(start 0.7874 0.4064)
			(end -0.7874 0.4064)
			(stroke
				(width 0.1524)
				(type default)
			)
			(layer "F.SilkS")
		)
		(fp_line
			(start -0.7874 0.4064)
			(end -0.7874 -0.4064)
			(stroke
				(width 0.1524)
				(type default)
			)
			(layer "F.SilkS")
		)
		(fp_line
			(start -0.12065 -0.305054)
			(end -0.12065 -0.2794)
			(stroke
				(width 0.1)
				(type default)
			)
			(layer "F.Fab")
		)
		(fp_line
			(start -0.67945 -0.305054)
			(end -0.12065 -0.305054)
			(stroke
				(width 0.1)
				(type default)
			)
			(layer "F.Fab")
		)
		(fp_line
			(start 0.67945 -0.3048)
			(end 0.67945 0.3048)
			(stroke
				(width 0.1)
				(type default)
			)
			(layer "F.Fab")
		)
		(fp_line
			(start 0.12065 -0.3048)
			(end 0.67945 -0.3048)
			(stroke
				(width 0.1)
				(type default)
			)
			(layer "F.Fab")
		)
		(fp_line
			(start 0.12065 -0.2794)
			(end 0.12065 -0.3048)
			(stroke
				(width 0.1)
				(type default)
			)
			(layer "F.Fab")
		)
		(fp_line
			(start -0.12065 -0.2794)
			(end 0.12065 -0.2794)
			(stroke
				(width 0.1)
				(type default)
			)
			(layer "F.Fab")
		)
		(fp_line
			(start 0.120396 0.2794)
			(end -0.12065 0.2794)
			(stroke
				(width 0.1)
				(type default)
			)
			(layer "F.Fab")
		)
		(fp_line
			(start -0.12065 0.2794)
			(end -0.12065 0.3048)
			(stroke
				(width 0.1)
				(type default)
			)
			(layer "F.Fab")
		)
		(fp_line
			(start 0.67945 0.3048)
			(end 0.120396 0.3048)
			(stroke
				(width 0.1)
				(type default)
			)
			(layer "F.Fab")
		)
		(fp_line
			(start 0.120396 0.3048)
			(end 0.120396 0.2794)
			(stroke
				(width 0.1)
				(type default)
			)
			(layer "F.Fab")
		)
		(fp_line
			(start -0.12065 0.3048)
			(end -0.67945 0.3048)
			(stroke
				(width 0.1)
				(type default)
			)
			(layer "F.Fab")
		)
		(fp_line
			(start -0.67945 0.3048)
			(end -0.67945 -0.305054)
			(stroke
				(width 0.1)
				(type default)
			)
			(layer "F.Fab")
		)
		(pad "1" smd circle
			(at -0.40005 0 90)
			(size 0 0)
			(layers "F.Cu" "F.Mask" "F.Paste")
			(net "VR_P5V_EN")
		)
		(pad "2" smd circle
			(at 0.40005 0 90)
			(size 0 0)
			(layers "F.Cu" "F.Mask" "F.Paste")
			(net "GND")
		)
	)
	(footprint ""
		(layer "F.Cu")
		(at 430.186592 -118.815104 -90)
		(property "Reference" "PC630"
			(at 0 0 270)
			(layer "F.SilkS")
			(hide yes)
			(effects
				(font
					(size 1.27 1.27)
				)
			)
		)
		(property "Value" ""
			(at 0 0 270)
			(layer "F.Fab")
			(effects
				(font
					(size 1.27 1.27)
				)
			)
		)
		(duplicate_pad_numbers_are_jumpers no)
		(fp_line
			(start -0.7874 0.4064)
			(end -0.7874 -0.4064)
			(stroke
				(width 0.1524)
				(type default)
			)
			(layer "F.SilkS")
		)
		(fp_line
			(start 0.7874 0.4064)
			(end -0.7874 0.4064)
			(stroke
				(width 0.1524)
				(type default)
			)
			(layer "F.SilkS")
		)
		(fp_line
			(start -0.7874 -0.4064)
			(end 0.7874 -0.4064)
			(stroke
				(width 0.1524)
				(type default)
			)
			(layer "F.SilkS")
		)
		(fp_line
			(start 0.7874 -0.4064)
			(end 0.7874 0.4064)
			(stroke
				(width 0.1524)
				(type default)
			)
			(layer "F.SilkS")
		)
		(fp_line
			(start -0.67945 0.3048)
			(end -0.67945 -0.305054)
			(stroke
				(width 0.1)
				(type default)
			)
			(layer "F.Fab")
		)
		(fp_line
			(start -0.12065 0.3048)
			(end -0.67945 0.3048)
			(stroke
				(width 0.1)
				(type default)
			)
			(layer "F.Fab")
		)
		(fp_line
			(start 0.120396 0.3048)
			(end 0.120396 0.2794)
			(stroke
				(width 0.1)
				(type default)
			)
			(layer "F.Fab")
		)
		(fp_line
			(start 0.67945 0.3048)
			(end 0.120396 0.3048)
			(stroke
				(width 0.1)
				(type default)
			)
			(layer "F.Fab")
		)
		(fp_line
			(start -0.12065 0.2794)
			(end -0.12065 0.3048)
			(stroke
				(width 0.1)
				(type default)
			)
			(layer "F.Fab")
		)
		(fp_line
			(start 0.120396 0.2794)
			(end -0.12065 0.2794)
			(stroke
				(width 0.1)
				(type default)
			)
			(layer "F.Fab")
		)
		(fp_line
			(start -0.12065 -0.2794)
			(end 0.12065 -0.2794)
			(stroke
				(width 0.1)
				(type default)
			)
			(layer "F.Fab")
		)
		(fp_line
			(start 0.12065 -0.2794)
			(end 0.12065 -0.3048)
			(stroke
				(width 0.1)
				(type default)
			)
			(layer "F.Fab")
		)
		(fp_line
			(start 0.12065 -0.3048)
			(end 0.67945 -0.3048)
			(stroke
				(width 0.1)
				(type default)
			)
			(layer "F.Fab")
		)
		(fp_line
			(start 0.67945 -0.3048)
			(end 0.67945 0.3048)
			(stroke
				(width 0.1)
				(type default)
			)
			(layer "F.Fab")
		)
		(fp_line
			(start -0.67945 -0.305054)
			(end -0.12065 -0.305054)
			(stroke
				(width 0.1)
				(type default)
			)
			(layer "F.Fab")
		)
		(fp_line
			(start -0.12065 -0.305054)
			(end -0.12065 -0.2794)
			(stroke
				(width 0.1)
				(type default)
			)
			(layer "F.Fab")
		)
		(pad "1" smd circle
			(at -0.40005 0 270)
			(size 0 0)
			(layers "F.Cu" "F.Mask" "F.Paste")
			(net "PVCCD_HV_CPU0_VREF")
		)
		(pad "2" smd circle
			(at 0.40005 0 270)
			(size 0 0)
			(layers "F.Cu" "F.Mask" "F.Paste")
			(net "GND")
		)
	)
	(footprint ""
		(layer "F.Cu")
		(at 121.708926 -122.096784 90)
		(property "Reference" "R935"
			(at 0 0 90)
			(layer "F.SilkS")
			(hide yes)
			(effects
				(font
					(size 1.27 1.27)
				)
			)
		)
		(property "Value" ""
			(at 0 0 90)
			(layer "F.Fab")
			(effects
				(font
					(size 1.27 1.27)
				)
			)
		)
		(duplicate_pad_numbers_are_jumpers no)
		(fp_line
			(start 0.7874 -0.4064)
			(end 0.7874 0.4064)
			(stroke
				(width 0.1524)
				(type default)
			)
			(layer "F.SilkS")
		)
		(fp_line
			(start -0.7874 -0.4064)
			(end 0.7874 -0.4064)
			(stroke
				(width 0.1524)
				(type default)
			)
			(layer "F.SilkS")
		)
		(fp_line
			(start 0.7874 0.4064)
			(end -0.7874 0.4064)
			(stroke
				(width 0.1524)
				(type default)
			)
			(layer "F.SilkS")
		)
		(fp_line
			(start -0.7874 0.4064)
			(end -0.7874 -0.4064)
			(stroke
				(width 0.1524)
				(type default)
			)
			(layer "F.SilkS")
		)
		(fp_line
			(start -0.12065 -0.305054)
			(end -0.12065 -0.2794)
			(stroke
				(width 0.1)
				(type default)
			)
			(layer "F.Fab")
		)
		(fp_line
			(start -0.67945 -0.305054)
			(end -0.12065 -0.305054)
			(stroke
				(width 0.1)
				(type default)
			)
			(layer "F.Fab")
		)
		(fp_line
			(start 0.67945 -0.3048)
			(end 0.67945 0.3048)
			(stroke
				(width 0.1)
				(type default)
			)
			(layer "F.Fab")
		)
		(fp_line
			(start 0.12065 -0.3048)
			(end 0.67945 -0.3048)
			(stroke
				(width 0.1)
				(type default)
			)
			(layer "F.Fab")
		)
		(fp_line
			(start 0.12065 -0.2794)
			(end 0.12065 -0.3048)
			(stroke
				(width 0.1)
				(type default)
			)
			(layer "F.Fab")
		)
		(fp_line
			(start -0.12065 -0.2794)
			(end 0.12065 -0.2794)
			(stroke
				(width 0.1)
				(type default)
			)
			(layer "F.Fab")
		)
		(fp_line
			(start 0.120396 0.2794)
			(end -0.12065 0.2794)
			(stroke
				(width 0.1)
				(type default)
			)
			(layer "F.Fab")
		)
		(fp_line
			(start -0.12065 0.2794)
			(end -0.12065 0.3048)
			(stroke
				(width 0.1)
				(type default)
			)
			(layer "F.Fab")
		)
		(fp_line
			(start 0.67945 0.3048)
			(end 0.120396 0.3048)
			(stroke
				(width 0.1)
				(type default)
			)
			(layer "F.Fab")
		)
		(fp_line
			(start 0.120396 0.3048)
			(end 0.120396 0.2794)
			(stroke
				(width 0.1)
				(type default)
			)
			(layer "F.Fab")
		)
		(fp_line
			(start -0.12065 0.3048)
			(end -0.67945 0.3048)
			(stroke
				(width 0.1)
				(type default)
			)
			(layer "F.Fab")
		)
		(fp_line
			(start -0.67945 0.3048)
			(end -0.67945 -0.305054)
			(stroke
				(width 0.1)
				(type default)
			)
			(layer "F.Fab")
		)
		(pad "1" smd circle
			(at -0.40005 0 90)
			(size 0 0)
			(layers "F.Cu" "F.Mask" "F.Paste")
			(net "RST_CPU1_DRAM_CD_N")
		)
		(pad "2" smd circle
			(at 0.40005 0 90)
			(size 0 0)
			(layers "F.Cu" "F.Mask" "F.Paste")
			(net "GND")
		)
	)
	(footprint ""
		(layer "F.Cu")
		(at 176.17948 -421.350948)
		(property "Reference" "R2927"
			(at 0 0 0)
			(layer "F.SilkS")
			(hide yes)
			(effects
				(font
					(size 1.27 1.27)
				)
			)
		)
		(property "Value" ""
			(at 0 0 0)
			(layer "F.Fab")
			(effects
				(font
					(size 1.27 1.27)
				)
			)
		)
		(duplicate_pad_numbers_are_jumpers no)
		(fp_line
			(start -0.7874 -0.4064)
			(end 0.7874 -0.4064)
			(stroke
				(width 0.1524)
				(type default)
			)
			(layer "F.SilkS")
		)
		(fp_line
			(start -0.7874 0.4064)
			(end -0.7874 -0.4064)
			(stroke
				(width 0.1524)
				(type default)
			)
			(layer "F.SilkS")
		)
		(fp_line
			(start 0.7874 -0.4064)
			(end 0.7874 0.4064)
			(stroke
				(width 0.1524)
				(type default)
			)
			(layer "F.SilkS")
		)
		(fp_line
			(start 0.7874 0.4064)
			(end -0.7874 0.4064)
			(stroke
				(width 0.1524)
				(type default)
			)
			(layer "F.SilkS")
		)
		(fp_line
			(start -0.67945 -0.305054)
			(end -0.12065 -0.305054)
			(stroke
				(width 0.1)
				(type default)
			)
			(layer "F.Fab")
		)
		(fp_line
			(start -0.67945 0.3048)
			(end -0.67945 -0.305054)
			(stroke
				(width 0.1)
				(type default)
			)
			(layer "F.Fab")
		)
		(fp_line
			(start -0.12065 -0.305054)
			(end -0.12065 -0.2794)
			(stroke
				(width 0.1)
				(type default)
			)
			(layer "F.Fab")
		)
		(fp_line
			(start -0.12065 -0.2794)
			(end 0.12065 -0.2794)
			(stroke
				(width 0.1)
				(type default)
			)
			(layer "F.Fab")
		)
		(fp_line
			(start -0.12065 0.2794)
			(end -0.12065 0.3048)
			(stroke
				(width 0.1)
				(type default)
			)
			(layer "F.Fab")
		)
		(fp_line
			(start -0.12065 0.3048)
			(end -0.67945 0.3048)
			(stroke
				(width 0.1)
				(type default)
			)
			(layer "F.Fab")
		)
		(fp_line
			(start 0.120396 0.2794)
			(end -0.12065 0.2794)
			(stroke
				(width 0.1)
				(type default)
			)
			(layer "F.Fab")
		)
		(fp_line
			(start 0.120396 0.3048)
			(end 0.120396 0.2794)
			(stroke
				(width 0.1)
				(type default)
			)
			(layer "F.Fab")
		)
		(fp_line
			(start 0.12065 -0.3048)
			(end 0.67945 -0.3048)
			(stroke
				(width 0.1)
				(type default)
			)
			(layer "F.Fab")
		)
		(fp_line
			(start 0.12065 -0.2794)
			(end 0.12065 -0.3048)
			(stroke
				(width 0.1)
				(type default)
			)
			(layer "F.Fab")
		)
		(fp_line
			(start 0.67945 -0.3048)
			(end 0.67945 0.3048)
			(stroke
				(width 0.1)
				(type default)
			)
			(layer "F.Fab")
		)
		(fp_line
			(start 0.67945 0.3048)
			(end 0.120396 0.3048)
			(stroke
				(width 0.1)
				(type default)
			)
			(layer "F.Fab")
		)
		(pad "1" smd circle
			(at -0.40005 0)
			(size 0 0)
			(layers "F.Cu" "F.Mask" "F.Paste")
			(net "RST_SWB_BIC_BUF_R_N")
		)
		(pad "2" smd circle
			(at 0.40005 0)
			(size 0 0)
			(layers "F.Cu" "F.Mask" "F.Paste")
			(net "GND")
		)
	)
	(footprint ""
		(layer "F.Cu")
		(at 318.8081 -76.585064 -90)
		(property "Reference" "R2242"
			(at 0 0 270)
			(layer "F.SilkS")
			(hide yes)
			(effects
				(font
					(size 1.27 1.27)
				)
			)
		)
		(property "Value" ""
			(at 0 0 270)
			(layer "F.Fab")
			(effects
				(font
					(size 1.27 1.27)
				)
			)
		)
		(duplicate_pad_numbers_are_jumpers no)
		(fp_line
			(start -0.7874 0.4064)
			(end -0.7874 -0.4064)
			(stroke
				(width 0.1524)
				(type default)
			)
			(layer "F.SilkS")
		)
		(fp_line
			(start 0.7874 0.4064)
			(end -0.7874 0.4064)
			(stroke
				(width 0.1524)
				(type default)
			)
			(layer "F.SilkS")
		)
		(fp_line
			(start -0.7874 -0.4064)
			(end 0.7874 -0.4064)
			(stroke
				(width 0.1524)
				(type default)
			)
			(layer "F.SilkS")
		)
		(fp_line
			(start 0.7874 -0.4064)
			(end 0.7874 0.4064)
			(stroke
				(width 0.1524)
				(type default)
			)
			(layer "F.SilkS")
		)
		(fp_line
			(start -0.67945 0.3048)
			(end -0.67945 -0.305054)
			(stroke
				(width 0.1)
				(type default)
			)
			(layer "F.Fab")
		)
		(fp_line
			(start -0.12065 0.3048)
			(end -0.67945 0.3048)
			(stroke
				(width 0.1)
				(type default)
			)
			(layer "F.Fab")
		)
		(fp_line
			(start 0.120396 0.3048)
			(end 0.120396 0.2794)
			(stroke
				(width 0.1)
				(type default)
			)
			(layer "F.Fab")
		)
		(fp_line
			(start 0.67945 0.3048)
			(end 0.120396 0.3048)
			(stroke
				(width 0.1)
				(type default)
			)
			(layer "F.Fab")
		)
		(fp_line
			(start -0.12065 0.2794)
			(end -0.12065 0.3048)
			(stroke
				(width 0.1)
				(type default)
			)
			(layer "F.Fab")
		)
		(fp_line
			(start 0.120396 0.2794)
			(end -0.12065 0.2794)
			(stroke
				(width 0.1)
				(type default)
			)
			(layer "F.Fab")
		)
		(fp_line
			(start -0.12065 -0.2794)
			(end 0.12065 -0.2794)
			(stroke
				(width 0.1)
				(type default)
			)
			(layer "F.Fab")
		)
		(fp_line
			(start 0.12065 -0.2794)
			(end 0.12065 -0.3048)
			(stroke
				(width 0.1)
				(type default)
			)
			(layer "F.Fab")
		)
		(fp_line
			(start 0.12065 -0.3048)
			(end 0.67945 -0.3048)
			(stroke
				(width 0.1)
				(type default)
			)
			(layer "F.Fab")
		)
		(fp_line
			(start 0.67945 -0.3048)
			(end 0.67945 0.3048)
			(stroke
				(width 0.1)
				(type default)
			)
			(layer "F.Fab")
		)
		(fp_line
			(start -0.67945 -0.305054)
			(end -0.12065 -0.305054)
			(stroke
				(width 0.1)
				(type default)
			)
			(layer "F.Fab")
		)
		(fp_line
			(start -0.12065 -0.305054)
			(end -0.12065 -0.2794)
			(stroke
				(width 0.1)
				(type default)
			)
			(layer "F.Fab")
		)
		(pad "1" smd circle
			(at -0.40005 0 270)
			(size 0 0)
			(layers "F.Cu" "F.Mask" "F.Paste")
			(net "P1V05_PCH_AUX")
		)
		(pad "2" smd circle
			(at 0.40005 0 270)
			(size 0 0)
			(layers "F.Cu" "F.Mask" "F.Paste")
			(net "FM_BOARD_SKU_ID0")
		)
	)
)
